#ISCELL
  mstr_misc dns *
  *
#ISCELL
  pure_quanta quanta_title_block_c *
  *
#CELL
  pure_quanta q_res *
  page163_i100
#CELL
  pure_quanta q_res *
  page163_i101
#CELL
  pure_quanta q_res *
  page163_i102
#CELL
  pure_quanta q_res *
  page163_i103
#CELL
  pure_quanta q_res *
  page163_i104
#ISCELL
  logical_power universal_gnd *
  page163_i105
#ISCELL
  standard offpage *
  page163_i106
#ISCELL
  logical_power universal_gnd *
  page163_i107
#CELL
  pure_quanta q_cap *
  page163_i108
#CELL
  pure_quanta q_res *
  page163_i109
#CELL
  pure_quanta q_res *
  page163_i110
#ISCELL
  standard offpage *
  page163_i111
#ISCELL
  logical_power universal_power *
  page163_i112
#ISCELL
  logical_power universal_power *
  page163_i113
#CELL
  pure_quanta q_cap *
  page163_i114
#ISCELL
  logical_power universal_gnd *
  page163_i115
#ISCELL
  logical_power universal_power *
  page163_i117
#ISCELL
  logical_power universal_power *
  page163_i118
#ISCELL
  logical_power universal_power *
  page163_i119
#ISCELL
  logical_power universal_power *
  page163_i120
#ISCELL
  logical_power universal_power *
  page163_i121
#CELL
  pure_quanta q_res *
  page163_i122
#ISCELL
  logical_power universal_power *
  page163_i123
#CELL
  pure_quanta q_res *
  page163_i124
#ISCELL
  logical_power universal_power *
  page163_i125
#CELL
  pure_quanta q_res *
  page163_i126
#CELL
  pure_quanta q_res *
  page163_i127
#CELL
  pure_quanta q_res *
  page163_i128
#CELL
  pure_quanta q_res *
  page163_i129
#ISCELL
  logical_power universal_power *
  page163_i24
#CELL
  pure_quanta q_cap *
  page163_i26
#ISCELL
  logical_power universal_gnd *
  page163_i27
#ISCELL
  standard offpage *
  page163_i29
#ISCELL
  standard offpage *
  page163_i30
#ISCELL
  logical_power universal_gnd *
  page163_i31
#ISCELL
  logical_power universal_power *
  page163_i32
#CELL
  pure_quanta q_res *
  page163_i33
#CELL
  pure_quanta q_res *
  page163_i35
#CELL
  pure_quanta q_res *
  page163_i36
#CELL
  pure_quanta q_res *
  page163_i37
#CELL
  pure_quanta q_res *
  page163_i38
#ISCELL
  logical_power universal_gnd *
  page163_i39
#ISCELL
  logical_power universal_gnd *
  page163_i40
#CELL
  pure_quanta q_res *
  page163_i41
#CELL
  pure_quanta q_cap *
  page163_i42
#ISCELL
  logical_power universal_power *
  page163_i43
#ISCELL
  standard offpage *
  page163_i44
#CELL
  pure_quanta q_res *
  page163_i45
#CELL
  pure_quanta ina230airgtr *
  page163_i46
#CELL
  pure_quanta q_cap *
  page163_i49
#ISCELL
  logical_power universal_gnd *
  page163_i50
#ISCELL
  standard offpage *
  page163_i52
#ISCELL
  standard offpage *
  page163_i53
#ISCELL
  logical_power universal_gnd *
  page163_i54
#CELL
  pure_quanta q_res *
  page163_i56
#CELL
  pure_quanta q_res *
  page163_i58
#CELL
  pure_quanta q_res *
  page163_i59
#CELL
  pure_quanta q_res *
  page163_i60
#CELL
  pure_quanta q_res *
  page163_i61
#ISCELL
  logical_power universal_gnd *
  page163_i62
#ISCELL
  logical_power universal_gnd *
  page163_i63
#CELL
  pure_quanta q_res *
  page163_i64
#CELL
  pure_quanta q_cap *
  page163_i65
#ISCELL
  logical_power universal_power *
  page163_i66
#ISCELL
  standard offpage *
  page163_i67
#CELL
  pure_quanta q_res *
  page163_i68
#CELL
  pure_quanta ina230airgtr *
  page163_i69
#CELL
  pure_quanta q_cap *
  page163_i71
#CELL
  pure_quanta q_cap *
  page163_i72
#ISCELL
  logical_power universal_power *
  page163_i76
#ISCELL
  logical_power universal_power *
  page163_i85
#CELL
  pure_quanta q_res *
  page163_i86
#CELL
  pure_quanta q_res *
  page163_i87
#ISCELL
  logical_power universal_power *
  page163_i88
#CELL
  pure_quanta q_res *
  page163_i89
#CELL
  pure_quanta q_res *
  page163_i90
#CELL
  pure_quanta ina230airgtr *
  page163_i94
#ISCELL
  standard offpage *
  page163_i95
#CELL
  pure_quanta q_res *
  page163_i96
#ISCELL
  logical_power universal_power *
  page163_i97
#CELL
  pure_quanta q_cap *
  page163_i98
#ISCELL
  logical_power universal_gnd *
  page163_i99
